# SCM (Grand Teton) — schematic netlist excerpt (pin names and nets, part order shuffled) for the footprints in the layout excerpt that follows; sources: Cadence DE-HDL packaged netlist, KiCad conversion of 12092022_DA0F0TMDCD0_F0T_Management_Board_D_brd_V3_OCP.brd

R458  Q_RES  33.2 1% CHIP  pkg 0402LF  page 13 : A = FM_DEBUG_PORT_PRSNT_R1_N ; B = FM_DEBUG_PORT_PRSNT_N
L16  Q_INDUCTOR  BLM18PG121SN1D/2000MA IND  pkg SMLF  page 17 : \1\ = P1V8_AUX ; \2\ = P1V8_STBY_DP_VCC18A

(kicad_pcb
	(version 20260206)
	(generator "pcbnew")
	(generator_version "10.0")
	(general
		(thickness 1.6)
		(legacy_teardrops no)
	)
	(paper "A4")
	(title_block
		(title "12092022_DA0F0TMDCD0_F0T_Management_Board_D_brd_V3_OCP.brd")
		(comment 1 "Grand Teton / footprints 881-882 of 1440")
	)
	(layers
		(0 "F.Cu" signal "TOP")
		(4 "In1.Cu" signal "GND")
		(6 "In2.Cu" signal "IN1")
		(8 "In3.Cu" signal "GND1")
		(10 "In4.Cu" signal "IN2")
		(12 "In5.Cu" signal "VCC")
		(14 "In6.Cu" signal "VCC1")
		(16 "In7.Cu" signal "IN3")
		(18 "In8.Cu" signal "GND2")
		(20 "In9.Cu" signal "IN4")
		(22 "In10.Cu" signal "GND3")
		(2 "B.Cu" signal "BOTTOM")
		(9 "F.Adhes" user "F.Adhesive")
		(11 "B.Adhes" user "B.Adhesive")
		(13 "F.Paste" user "Package Geometry/Pastemask Top")
		(15 "B.Paste" user "Package Geometry/Pastemask Bottom")
		(5 "F.SilkS" user "Ref Des/Silkscreen Top")
		(7 "B.SilkS" user "Ref Des/Silkscreen Bottom")
		(1 "F.Mask" user "Board Geometry/Soldermask Top")
		(3 "B.Mask" user "Board Geometry/Soldermask Bottom")
		(17 "Dwgs.User" user "User.Drawings")
		(19 "Cmts.User" user "User.Comments")
		(21 "Eco1.User" user "User.Eco1")
		(23 "Eco2.User" user "User.Eco2")
		(25 "Edge.Cuts" user "Board Geometry/Outline")
		(27 "Margin" user)
		(31 "F.CrtYd" user "Package Geometry/Place Bound Top")
		(29 "B.CrtYd" user "Package Geometry/Place Bound Bottom")
		(35 "F.Fab" user "Ref Des/Assembly Top")
		(33 "B.Fab" user "Ref Des/Assembly Bottom")
	)
	(footprint ""
		(layer "B.Cu")
		(at 72.13346 -65.40627 90)
		(property "Reference" "L16"
			(at 0 0 90)
			(layer "B.SilkS")
			(hide yes)
			(effects
				(font
					(size 1.27 1.27)
				)
				(justify mirror)
			)
		)
		(property "Value" ""
			(at 0 0 90)
			(layer "B.Fab")
			(effects
				(font
					(size 1.27 1.27)
				)
				(justify mirror)
			)
		)
		(duplicate_pad_numbers_are_jumpers no)
		(fp_line
			(start 1.27 -0.5842)
			(end -1.27 -0.5842)
			(stroke
				(width 0.1524)
				(type default)
			)
			(layer "B.SilkS")
		)
		(fp_line
			(start 1.27 -0.5588)
			(end 1.27 -0.5842)
			(stroke
				(width 0.1524)
				(type default)
			)
			(layer "B.SilkS")
		)
		(fp_line
			(start 1.27 0.5842)
			(end 1.27 -0.5842)
			(stroke
				(width 0.1524)
				(type default)
			)
			(layer "B.SilkS")
		)
		(fp_line
			(start 0.127 0.5842)
			(end 0.127 -0.5842)
			(stroke
				(width 0.1524)
				(type default)
			)
			(layer "B.SilkS")
		)
		(fp_line
			(start -0.127 0.5842)
			(end -0.127 -0.5842)
			(stroke
				(width 0.1524)
				(type default)
			)
			(layer "B.SilkS")
		)
		(fp_line
			(start -1.27 0.5842)
			(end -1.27 -0.5842)
			(stroke
				(width 0.1524)
				(type default)
			)
			(layer "B.SilkS")
		)
		(fp_line
			(start -1.27 0.5842)
			(end 1.27 0.5842)
			(stroke
				(width 0.1524)
				(type default)
			)
			(layer "B.SilkS")
		)
		(fp_line
			(start 0.9144 -0.508)
			(end -0.9144 -0.508)
			(stroke
				(width 0.1)
				(type default)
			)
			(layer "B.Fab")
		)
		(fp_line
			(start -0.9144 -0.508)
			(end -0.9144 -0.406654)
			(stroke
				(width 0.1)
				(type default)
			)
			(layer "B.Fab")
		)
		(fp_line
			(start 1.194308 -0.406654)
			(end 0.9144 -0.406654)
			(stroke
				(width 0.1)
				(type default)
			)
			(layer "B.Fab")
		)
		(fp_line
			(start 0.9144 -0.406654)
			(end 0.9144 -0.508)
			(stroke
				(width 0.1)
				(type default)
			)
			(layer "B.Fab")
		)
		(fp_line
			(start -0.9144 -0.406654)
			(end -1.1938 -0.406654)
			(stroke
				(width 0.1)
				(type default)
			)
			(layer "B.Fab")
		)
		(fp_line
			(start -1.1938 -0.406654)
			(end -1.1938 0.4064)
			(stroke
				(width 0.1)
				(type default)
			)
			(layer "B.Fab")
		)
		(fp_line
			(start -0.9144 0.4064)
			(end -0.9144 0.508)
			(stroke
				(width 0.1)
				(type default)
			)
			(layer "B.Fab")
		)
		(fp_line
			(start -1.1938 0.4064)
			(end -0.9144 0.4064)
			(stroke
				(width 0.1)
				(type default)
			)
			(layer "B.Fab")
		)
		(fp_line
			(start 1.194308 0.406654)
			(end 1.194308 -0.406654)
			(stroke
				(width 0.1)
				(type default)
			)
			(layer "B.Fab")
		)
		(fp_line
			(start 0.9144 0.406654)
			(end 1.194308 0.406654)
			(stroke
				(width 0.1)
				(type default)
			)
			(layer "B.Fab")
		)
		(fp_line
			(start 0.9144 0.508)
			(end 0.9144 0.406654)
			(stroke
				(width 0.1)
				(type default)
			)
			(layer "B.Fab")
		)
		(fp_line
			(start -0.9144 0.508)
			(end 0.9144 0.508)
			(stroke
				(width 0.1)
				(type default)
			)
			(layer "B.Fab")
		)
		(pad "1" smd rect
			(at 0.7366 0)
			(size 0.7112 0.8128)
			(layers "B.Cu" "B.Mask" "B.Paste")
			(net "P1V8_AUX")
		)
		(pad "2" smd rect
			(at -0.7366 0)
			(size 0.7112 0.8128)
			(layers "B.Cu" "B.Mask" "B.Paste")
			(net "P1V8_STBY_DP_VCC18A")
		)
	)
	(footprint ""
		(layer "B.Cu")
		(at 58.7375 -63.2333 -90)
		(property "Reference" "R458"
			(at 0 0 90)
			(layer "B.SilkS")
			(hide yes)
			(effects
				(font
					(size 1.27 1.27)
				)
				(justify mirror)
			)
		)
		(property "Value" ""
			(at 0 0 90)
			(layer "B.Fab")
			(effects
				(font
					(size 1.27 1.27)
				)
				(justify mirror)
			)
		)
		(duplicate_pad_numbers_are_jumpers no)
		(fp_line
			(start -0.7874 0.4064)
			(end 0.7874 0.4064)
			(stroke
				(width 0.1524)
				(type default)
			)
			(layer "B.SilkS")
		)
		(fp_line
			(start 0.7874 0.4064)
			(end 0.7874 -0.4064)
			(stroke
				(width 0.1524)
				(type default)
			)
			(layer "B.SilkS")
		)
		(fp_line
			(start -0.7874 -0.4064)
			(end -0.7874 0.4064)
			(stroke
				(width 0.1524)
				(type default)
			)
			(layer "B.SilkS")
		)
		(fp_line
			(start 0.7874 -0.4064)
			(end -0.7874 -0.4064)
			(stroke
				(width 0.1524)
				(type default)
			)
			(layer "B.SilkS")
		)
		(fp_line
			(start -0.67945 0.3048)
			(end -0.120396 0.3048)
			(stroke
				(width 0.1)
				(type default)
			)
			(layer "B.Fab")
		)
		(fp_line
			(start -0.120396 0.3048)
			(end -0.120396 0.2794)
			(stroke
				(width 0.1)
				(type default)
			)
			(layer "B.Fab")
		)
		(fp_line
			(start 0.12065 0.3048)
			(end 0.67945 0.3048)
			(stroke
				(width 0.1)
				(type default)
			)
			(layer "B.Fab")
		)
		(fp_line
			(start 0.67945 0.3048)
			(end 0.67945 -0.305054)
			(stroke
				(width 0.1)
				(type default)
			)
			(layer "B.Fab")
		)
		(fp_line
			(start -0.120396 0.2794)
			(end 0.12065 0.2794)
			(stroke
				(width 0.1)
				(type default)
			)
			(layer "B.Fab")
		)
		(fp_line
			(start 0.12065 0.2794)
			(end 0.12065 0.3048)
			(stroke
				(width 0.1)
				(type default)
			)
			(layer "B.Fab")
		)
		(fp_line
			(start -0.12065 -0.2794)
			(end -0.12065 -0.3048)
			(stroke
				(width 0.1)
				(type default)
			)
			(layer "B.Fab")
		)
		(fp_line
			(start 0.12065 -0.2794)
			(end -0.12065 -0.2794)
			(stroke
				(width 0.1)
				(type default)
			)
			(layer "B.Fab")
		)
		(fp_line
			(start -0.67945 -0.3048)
			(end -0.67945 0.3048)
			(stroke
				(width 0.1)
				(type default)
			)
			(layer "B.Fab")
		)
		(fp_line
			(start -0.12065 -0.3048)
			(end -0.67945 -0.3048)
			(stroke
				(width 0.1)
				(type default)
			)
			(layer "B.Fab")
		)
		(fp_line
			(start 0.12065 -0.305054)
			(end 0.12065 -0.2794)
			(stroke
				(width 0.1)
				(type default)
			)
			(layer "B.Fab")
		)
		(fp_line
			(start 0.67945 -0.305054)
			(end 0.12065 -0.305054)
			(stroke
				(width 0.1)
				(type default)
			)
			(layer "B.Fab")
		)
		(pad "1" smd circle
			(at 0.40005 0 90)
			(size 0 0)
			(layers "B.Cu" "B.Mask" "B.Paste")
			(net "FM_DEBUG_PORT_PRSNT_R1_N")
		)
		(pad "2" smd circle
			(at -0.40005 0 90)
			(size 0 0)
			(layers "B.Cu" "B.Mask" "B.Paste")
			(net "FM_DEBUG_PORT_PRSNT_N")
		)
	)
)
